FILE_TYPE = CONNECTIVITY;
{Allegro Design Entry HDL 17.2-2016 S081 (4005846) 1/11/2022}
"PAGE_NUMBER" = 121;
0"NC";
END.
